# BASEBOARD_FAB2 (Tioga Pass) — schematic netlist excerpt (pin names and nets, part order shuffled) for the footprints in the layout excerpt that follows; sources: Cadence DE-HDL packaged netlist, KiCad conversion of Wiwynn_Tioga_Pass_MB.brd

L8E1  INDUCTOR  2.2UH IND  pkg SM  page 241 : INA = VR_P5V_STBY_PHASE ; INB = P5V_STBY
R8C20  RES  20.0 1% CHIP  pkg 0402  page 138 : A = SMB_HOST_STBY_LVC3_SDA_R1 ; B = SMB_HOST_STBY_LVC3_SDA
U8E2  ADM809  IC  pkg SMLF  page 196 : RESET_N = PWRGD_P12V_HSC_DLY_R ; VCC = PWRGD_P12V_HSC

(kicad_pcb
	(version 20260206)
	(generator "pcbnew")
	(generator_version "10.0")
	(general
		(thickness 1.6)
		(legacy_teardrops no)
	)
	(paper "A4")
	(title_block
		(title "Wiwynn_Tioga_Pass_MB.brd")
		(comment 1 "Tioga Pass / footprints 851-853 of 4770")
	)
	(layers
		(0 "F.Cu" signal "TOP")
		(4 "In1.Cu" signal "L2GND")
		(6 "In2.Cu" signal "L3")
		(8 "In3.Cu" signal "L4GND")
		(10 "In4.Cu" signal "L5")
		(12 "In5.Cu" signal "L6GND")
		(14 "In6.Cu" signal "L7VCC")
		(16 "In7.Cu" signal "L8VCC")
		(18 "In8.Cu" signal "L9GND")
		(20 "In9.Cu" signal "L10")
		(22 "In10.Cu" signal "L11GND")
		(24 "In11.Cu" signal "L12")
		(26 "In12.Cu" signal "L13GND")
		(2 "B.Cu" signal "BOTTOM")
		(9 "F.Adhes" user "F.Adhesive")
		(11 "B.Adhes" user "B.Adhesive")
		(13 "F.Paste" user "Package Geometry/Pastemask Top")
		(15 "B.Paste" user "Package Geometry/Pastemask Bottom")
		(5 "F.SilkS" user "Ref Des/Silkscreen Top")
		(7 "B.SilkS" user "Ref Des/Silkscreen Bottom")
		(1 "F.Mask" user "Board Geometry/Soldermask Top")
		(3 "B.Mask" user "Board Geometry/Soldermask Bottom")
		(17 "Dwgs.User" user "User.Drawings")
		(19 "Cmts.User" user "User.Comments")
		(21 "Eco1.User" user "User.Eco1")
		(23 "Eco2.User" user "User.Eco2")
		(25 "Edge.Cuts" user "Board Geometry/Outline")
		(27 "Margin" user)
		(31 "F.CrtYd" user "Package Geometry/Place Bound Top")
		(29 "B.CrtYd" user "Package Geometry/Place Bound Bottom")
		(35 "F.Fab" user "Ref Des/Assembly Top")
		(33 "B.Fab" user "Ref Des/Assembly Bottom")
	)
	(footprint ""
		(layer "F.Cu")
		(at 397.750538 -75.050396)
		(property "Reference" "U8E2"
			(at 2.79908 2.95783 180)
			(unlocked yes)
			(layer "F.SilkS")
			(effects
				(font
					(size 0.7874 0.5842)
					(thickness 0.1524)
				)
				(justify left)
			)
		)
		(property "Value" ""
			(at 0 0 0)
			(layer "F.Fab")
			(effects
				(font
					(size 1.27 1.27)
				)
			)
		)
		(duplicate_pad_numbers_are_jumpers no)
		(fp_line
			(start 0.381 0.635)
			(end 0.381 1.27)
			(stroke
				(width 0.1524)
				(type default)
			)
			(layer "F.SilkS")
		)
		(fp_line
			(start 0.9525 -0.5715)
			(end 1.778 -0.5715)
			(stroke
				(width 0.1524)
				(type default)
			)
			(layer "F.SilkS")
		)
		(fp_line
			(start 0.9525 2.4765)
			(end 1.778 2.4765)
			(stroke
				(width 0.1524)
				(type default)
			)
			(layer "F.SilkS")
		)
		(fp_line
			(start 1.778 -0.5715)
			(end 1.778 0.3175)
			(stroke
				(width 0.1524)
				(type default)
			)
			(layer "F.SilkS")
		)
		(fp_line
			(start 1.778 2.4765)
			(end 1.778 1.5875)
			(stroke
				(width 0.1524)
				(type default)
			)
			(layer "F.SilkS")
		)
		(fp_circle
			(center -0.9525 -0.9271)
			(end -0.8255 -0.9271)
			(stroke
				(width 0.254)
				(type default)
			)
			(fill no)
			(layer "F.SilkS")
		)
		(fp_poly
			(pts
				(xy 1.778 2.4765) (xy 0.381 2.4765) (xy 0.381 -0.5715) (xy 1.778 -0.5715)
			)
			(stroke
				(width 0)
				(type default)
			)
			(fill no)
			(layer "F.CrtYd")
		)
		(fp_line
			(start 0.381 -0.5715)
			(end 0.381 2.4765)
			(stroke
				(width 0.1)
				(type default)
			)
			(layer "F.Fab")
		)
		(fp_line
			(start 0.381 2.4765)
			(end 1.778 2.4765)
			(stroke
				(width 0.1)
				(type default)
			)
			(layer "F.Fab")
		)
		(fp_line
			(start 1.778 -0.5715)
			(end 0.381 -0.5715)
			(stroke
				(width 0.1)
				(type default)
			)
			(layer "F.Fab")
		)
		(fp_line
			(start 1.778 2.4765)
			(end 1.778 -0.5715)
			(stroke
				(width 0.1)
				(type default)
			)
			(layer "F.Fab")
		)
		(fp_circle
			(center -0.9525 -0.9271)
			(end -0.8255 -0.9271)
			(stroke
				(width 0.254)
				(type default)
			)
			(fill no)
			(layer "F.Fab")
		)
		(pad "1" smd rect
			(at 0 0)
			(size 1.143 0.508)
			(layers "F.Cu" "F.Mask" "F.Paste")
			(net "GND")
		)
		(pad "2" smd rect
			(at 0 1.905)
			(size 1.143 0.508)
			(layers "F.Cu" "F.Mask" "F.Paste")
			(net "PWRGD_P12V_HSC_DLY_R")
		)
		(pad "3" smd rect
			(at 2.159 0.9525)
			(size 1.143 0.508)
			(layers "F.Cu" "F.Mask" "F.Paste")
			(net "PWRGD_P12V_HSC")
		)
	)
	(footprint ""
		(layer "F.Cu")
		(at 410.806138 -106.384598 90)
		(property "Reference" "R8C20"
			(at 0 0 90)
			(layer "F.SilkS")
			(hide yes)
			(effects
				(font
					(size 1.27 1.27)
				)
			)
		)
		(property "Value" ""
			(at 0 0 90)
			(layer "F.Fab")
			(effects
				(font
					(size 1.27 1.27)
				)
			)
		)
		(duplicate_pad_numbers_are_jumpers no)
		(fp_poly
			(pts
				(xy -0.2794 -0.1016) (xy 0.2794 -0.1016) (xy 0.2794 0.9906) (xy -0.2794 0.9906)
			)
			(stroke
				(width 0)
				(type default)
			)
			(fill no)
			(layer "F.CrtYd")
		)
		(fp_line
			(start 0.2794 -0.1016)
			(end -0.2794 -0.1016)
			(stroke
				(width 0.1)
				(type default)
			)
			(layer "F.Fab")
		)
		(fp_line
			(start -0.2794 -0.1016)
			(end -0.2794 0.9906)
			(stroke
				(width 0.1)
				(type default)
			)
			(layer "F.Fab")
		)
		(fp_line
			(start 0.2794 0.9906)
			(end 0.2794 -0.1016)
			(stroke
				(width 0.1)
				(type default)
			)
			(layer "F.Fab")
		)
		(fp_line
			(start -0.2794 0.9906)
			(end 0.2794 0.9906)
			(stroke
				(width 0.1)
				(type default)
			)
			(layer "F.Fab")
		)
		(pad "1" smd rect
			(at 0 0 90)
			(size 0.508 0.508)
			(layers "F.Cu" "F.Mask" "F.Paste")
			(net "SMB_HOST_STBY_LVC3_SDA_R1")
		)
		(pad "2" smd rect
			(at 0 0.889 90)
			(size 0.508 0.508)
			(layers "F.Cu" "F.Mask" "F.Paste")
			(net "SMB_HOST_STBY_LVC3_SDA")
		)
		(zone
			(layer "F.Cu")
			(hatch none 0.5)
			(connect_pads
				(clearance 0)
			)
			(min_thickness 0.25)
			(keepout
				(tracks allowed)
				(vias not_allowed)
				(pads allowed)
				(copperpour not_allowed)
				(footprints allowed)
			)
			(placement
				(enabled no)
				(sheetname "")
			)
			(fill
				(thermal_gap 0.5)
				(thermal_bridge_width 0.5)
				(island_removal_mode 0)
			)
			(polygon
				(pts
					(xy 411.060138 -106.130598) (xy 411.060138 -106.638598) (xy 411.441138 -106.638598) (xy 411.441138 -106.130598)
				)
			)
		)
		(zone
			(layer "F.Cu")
			(hatch none 0.5)
			(connect_pads
				(clearance 0)
			)
			(min_thickness 0.25)
			(keepout
				(tracks not_allowed)
				(vias allowed)
				(pads allowed)
				(copperpour not_allowed)
				(footprints allowed)
			)
			(placement
				(enabled no)
				(sheetname "")
			)
			(fill
				(thermal_gap 0.5)
				(thermal_bridge_width 0.5)
				(island_removal_mode 0)
			)
			(polygon
				(pts
					(xy 411.441138 -106.130598) (xy 411.441138 -106.638598) (xy 411.060138 -106.638598) (xy 411.060138 -106.130598)
				)
			)
		)
	)
	(footprint ""
		(layer "F.Cu")
		(at 398.39392 -68.59016 90)
		(property "Reference" "L8E1"
			(at -4.3434 7.72287 90)
			(unlocked yes)
			(layer "F.SilkS")
			(effects
				(font
					(size 0.7874 0.5842)
					(thickness 0.1524)
				)
				(justify left)
			)
		)
		(property "Value" ""
			(at 0 0 90)
			(layer "F.Fab")
			(effects
				(font
					(size 1.27 1.27)
				)
			)
		)
		(duplicate_pad_numbers_are_jumpers no)
		(fp_line
			(start 3.4036 -0.6731)
			(end 3.4036 6.1341)
			(stroke
				(width 0.1524)
				(type default)
			)
			(layer "F.SilkS")
		)
		(fp_line
			(start 2.5654 -0.6731)
			(end 3.4036 -0.6731)
			(stroke
				(width 0.1524)
				(type default)
			)
			(layer "F.SilkS")
		)
		(fp_line
			(start -3.4036 -0.6731)
			(end -2.5654 -0.6731)
			(stroke
				(width 0.1524)
				(type default)
			)
			(layer "F.SilkS")
		)
		(fp_line
			(start 3.4036 6.1341)
			(end 2.5654 6.1341)
			(stroke
				(width 0.1524)
				(type default)
			)
			(layer "F.SilkS")
		)
		(fp_line
			(start -2.5654 6.1341)
			(end -3.4036 6.1341)
			(stroke
				(width 0.1524)
				(type default)
			)
			(layer "F.SilkS")
		)
		(fp_line
			(start -3.4036 6.1341)
			(end -3.4036 -0.6731)
			(stroke
				(width 0.1524)
				(type default)
			)
			(layer "F.SilkS")
		)
		(fp_poly
			(pts
				(xy -3.4036 -0.6731) (xy -3.4036 6.1341) (xy 3.4036 6.1341) (xy 3.4036 -0.6731)
			)
			(stroke
				(width 0)
				(type default)
			)
			(fill no)
			(layer "F.CrtYd")
		)
		(fp_line
			(start 3.4036 -0.6731)
			(end 3.4036 6.1341)
			(stroke
				(width 0.1)
				(type default)
			)
			(layer "F.Fab")
		)
		(fp_line
			(start -3.4036 -0.6731)
			(end 3.4036 -0.6731)
			(stroke
				(width 0.1)
				(type default)
			)
			(layer "F.Fab")
		)
		(fp_line
			(start 3.4036 6.1341)
			(end -3.4036 6.1341)
			(stroke
				(width 0.1)
				(type default)
			)
			(layer "F.Fab")
		)
		(fp_line
			(start -3.4036 6.1341)
			(end -3.4036 -0.6731)
			(stroke
				(width 0.1)
				(type default)
			)
			(layer "F.Fab")
		)
		(pad "1" smd rect
			(at 0 0 90)
			(size 3.556 3.175)
			(layers "F.Cu" "F.Mask" "F.Paste")
			(net "VR_P5V_STBY_PHASE")
		)
		(pad "2" smd rect
			(at 0 5.461 90)
			(size 3.556 3.175)
			(layers "F.Cu" "F.Mask" "F.Paste")
			(net "P5V_STBY")
		)
	)
)
